G04 ================== begin FILE IDENTIFICATION RECORD ==================*
G04 Layout Name:  15750-1.brd*
G04 Film Name:    L6*
G04 File Format:  Gerber RS274X*
G04 File Origin:  Cadence Allegro 16.5-S056*
G04 Origin Date:  Fri Dec 30 13:21:39 2016*
G04 *
G04 Layer:  VIA CLASS/L6*
G04 Layer:  PIN/L6*
G04 Layer:  ETCH/L6*
G04 Layer:  DRAWING FORMAT/LAYER_L6*
G04 Layer:  DRAWING FORMAT/LAYER_PCB_STORY*
G04 *
G04 Offset:    (0.00 0.00)*
G04 Mirror:    No*
G04 Mode:      Positive*
G04 Rotation:  0*
G04 FullContactRelief:  No*
G04 UndefLineWidth:     6.00*
G04 ================== end FILE IDENTIFICATION RECORD ====================*
%FSLAX35Y35*MOIN*%
%IR0*IPPOS*OFA0.00000B0.00000*MIA0B0*SFA1.00000B1.00000*%
%ADD12C,.02*%
%ADD11C,.022*%
%ADD13C,.056*%
%ADD10C,.156*%
%ADD14C,.006*%
%ADD15C,.00525*%
%ADD22C,.03204*%
%ADD23C,.08004*%
%ADD21C,.04404*%
%ADD20C,.04604*%
%ADD17C,.06804*%
%ADD16C,.08704*%
%ADD18C,.08904*%
%ADD19C,.18004*%
G75*
%LPD*%
G75*
G36*
G01X223819Y1904D02*
G02X217849Y7874I0J5970D01*
G01Y258071D01*
G03X208071Y267849I-9778J0D01*
G01X7874D01*
G02X1904Y273819I0J5970D01*
G01Y355551D01*
G02X7874Y361521I5970J0D01*
G01X341535D01*
G02X347505Y355551I0J-5970D01*
G01Y279500D01*
X347005Y279000D01*
X338000D01*
X335500Y276500D01*
Y218000D01*
X338000Y215500D01*
X347005D01*
X347505Y215000D01*
Y195925D01*
G02X347441Y195861I-64J0D01*
G01X321062D01*
G03X317190Y191989I1J-3873D01*
G01Y175256D01*
G03X321063Y171383I3873J0D01*
G01X323938D01*
G02X324212Y170691I0J-400D01*
G03X323957Y170379I1032J-1104D01*
G01X323945Y170359D01*
X323842Y170257D01*
G02X323500Y170114I-343J340D01*
G01X321173D01*
G03X319457Y170854I-1735J-1664D01*
G01X317866D01*
G03X316142Y170114I11J-2404D01*
G01X315063D01*
G03X313347Y170854I-1735J-1664D01*
G01X311756D01*
G03X310032Y170114I11J-2404D01*
G01X308953D01*
G03X307237Y170854I-1735J-1664D01*
G01X305646D01*
G03X303922Y170114I11J-2404D01*
G01X300458D01*
X300212Y170360D01*
X300211Y170441D01*
G03X299519Y172098I-2404J-31D01*
G03X299512Y172105I-1039J-1032D01*
G01X298395Y173223D01*
G03X296734Y173918I-1691J-1709D01*
G01X296652Y173919D01*
X295892Y174679D01*
X295891Y174761D01*
G03X295199Y176418I-2404J-31D01*
G03X295192Y176426I-1104J-959D01*
G01X294075Y177543D01*
G03X292413Y178239I-1692J-1709D01*
G01X292331Y178240D01*
X291571Y179000D01*
X291570Y179082D01*
G03X290881Y180737I-2404J-30D01*
G03X290871Y180747I-1040J-1030D01*
G01X289754Y181863D01*
G03X288093Y182559I-1692J-1708D01*
G01X288011Y182560D01*
X287652Y182919D01*
G02X287464Y183372I453J454D01*
G01Y183994D01*
X287521Y184053D01*
G03X288204Y185712I-1721J1679D01*
G01Y187303D01*
G03X287464Y189027I-2404J-11D01*
G01Y190106D01*
G03X288204Y191822I-1664J1735D01*
G01Y193413D01*
G03X287927Y194523I-2404J-10D01*
G01X287904Y194567D01*
Y194816D01*
X288200D01*
G02X289424Y194635I2J-4218D01*
G03X293312Y195360I1876J726D01*
G01Y198561D01*
G03X289442Y199331I-2012J0D01*
G02X287500Y199020I-1943J5911D01*
G01X287184D01*
G03X284557Y197933I-1J-3715D01*
G01X284494Y197869D01*
G03X283260Y194891I2981J-2980D01*
G01Y183370D01*
G03X284679Y179945I4845J1D01*
G01X290870Y173754D01*
X297063Y167561D01*
X297492Y167133D01*
G03X300449Y165910I2960J2971D01*
G01X322000D01*
G02X324181Y165363I2J-4614D01*
G03X325720Y165002I1064J1074D01*
G02X326246Y164623I126J-379D01*
G01Y161952D01*
G02X325720Y161573I-400J0D01*
G03X323732Y160138I-476J-1435D01*
G01Y156988D01*
G03X325720Y155553I1512J0D01*
G02X326246Y155174I126J-379D01*
G01Y152493D01*
G02X325719Y152114I-400J0D01*
G03X324401Y149446I-475J-1425D01*
G02Y148783I-224J-332D01*
G03X325719Y146115I843J-1243D01*
G02X326246Y145736I127J-379D01*
G01Y111558D01*
G02X325720Y111179I-400J0D01*
G03X323732Y109744I-476J-1435D01*
G01Y106595D01*
G03X325720Y105160I1512J0D01*
G02X326246Y104781I126J-379D01*
G01Y102110D01*
G02X325720Y101731I-400J0D01*
G03X323732Y100296I-476J-1435D01*
G01Y97146D01*
G03X325720Y95711I1512J0D01*
G02X326246Y95332I126J-379D01*
G01Y92661D01*
G02X325720Y92282I-400J0D01*
G03X323732Y90847I-476J-1435D01*
G01Y87697D01*
G03X325720Y86262I1512J0D01*
G02X326246Y85883I126J-379D01*
G01Y83212D01*
G02X325720Y82833I-400J0D01*
G03X323732Y81399I-476J-1435D01*
G01Y78248D01*
G03X325720Y76813I1512J0D01*
G02X326246Y76434I126J-379D01*
G01Y73763D01*
G02X325720Y73384I-400J0D01*
G03X323732Y71949I-476J-1435D01*
G01Y68799D01*
G03X325720Y67364I1512J0D01*
G02X326246Y66985I126J-379D01*
G01Y64314D01*
G02X325720Y63935I-400J0D01*
G03X323732Y62501I-476J-1435D01*
G01Y59351D01*
G03X325720Y57916I1512J0D01*
G02X326246Y57537I126J-379D01*
G01Y55582D01*
G02X325753Y55193I-400J0D01*
G03X323581Y51608I-509J-2142D01*
G02Y51345I-151J-132D01*
G03X325753Y47760I1663J-1443D01*
G02X326246Y47371I93J-389D01*
G01Y46004D01*
G02X326181Y45939I-65J0D01*
G01X321062D01*
G03X317190Y42067I1J-3873D01*
G01Y25334D01*
G03X321062Y21462I3873J1D01*
G01X347441D01*
G02X347505Y21398I0J-64D01*
G01Y1968D01*
G02X347441Y1904I-64J0D01*
G01X223819D01*
G37*
%LPC*%
G75*
G36*
G01X260307Y169557D02*
X266441Y163422D01*
X268140D01*
G02Y159020I0J-2201D01*
G01X264617D01*
X257193Y166443D01*
G02X260307Y169557I1557J1557D01*
G37*
G36*
G01X110981Y336130D02*
G03X111519I269J296D01*
G02X114693Y335909I1481J-1630D01*
G03X115307I307J255D01*
G02X118693I1693J-1409D01*
G03X119307I307J255D01*
G02Y333091I1693J-1409D01*
G03X118693I-307J-255D01*
G02X115307I-1693J1409D01*
G03X114693I-307J-255D01*
G02X111519Y332870I-1693J1409D01*
G03X110981I-269J-296D01*
G02Y336130I-1481J1630D01*
G37*
G36*
G01X220607Y323452D02*
G03X220015I-296J-269D01*
G02Y326548I-1704J1548D01*
G03X220607I296J269D01*
G02Y323452I1704J-1548D01*
G37*
G36*
G01X139975Y323112D02*
G03X139336I-320J-241D01*
G02Y325888I-1836J1388D01*
G03X139975I320J241D01*
G02X143515Y326048I1836J-1388D01*
G03X144107I296J269D01*
G02X147515I1704J-1548D01*
G03X148107I296J269D01*
G02X151515I1704J-1548D01*
G03X152107I296J269D01*
G02X155515I1704J-1548D01*
G03X156107I296J269D01*
G02X159515I1704J-1548D01*
G03X160107I296J269D01*
G02X163515I1704J-1548D01*
G03X164107I296J269D01*
G02X167515I1704J-1548D01*
G03X168107I296J269D01*
G02Y322952I1704J-1548D01*
G03X167515I-296J-269D01*
G02X164107I-1704J1548D01*
G03X163515I-296J-269D01*
G02X160107I-1704J1548D01*
G03X159515I-296J-269D01*
G02X156107I-1704J1548D01*
G03X155515I-296J-269D01*
G02X152107I-1704J1548D01*
G03X151515I-296J-269D01*
G02X148107I-1704J1548D01*
G03X147515I-296J-269D01*
G02X144107I-1704J1548D01*
G03X143515I-296J-269D01*
G02X139975Y323112I-1704J1548D01*
G37*
G36*
G01X118588Y313418D02*
G03X118032I-278J-287D01*
G02Y316582I-1532J1582D01*
G03X118588I278J287D01*
G02Y313418I1532J-1582D01*
G37*
G36*
G01X90564Y310049D02*
G03X90410Y310587I-352J190D01*
G02X93436Y311451I1090J1913D01*
G03X93590Y310913I352J-190D01*
G02X90564Y310049I-1090J-1913D01*
G37*
G36*
G01X202557Y312500D02*
G02Y309500I-1746J-1500D01*
G02X199065I-1746J-1500D01*
G02Y312500I1746J1500D01*
G02Y315500I1746J1500D01*
G02X202557I1746J1500D01*
G02Y312500I-1746J-1500D01*
G37*
G36*
G01X140796Y297952D02*
G03X140204I-296J-269D01*
G02X136952Y301204I-1704J1548D01*
G03Y301796I-269J296D01*
G02Y305204I1548J1704D01*
G03Y305796I-269J296D01*
G02X136796Y305952I1548J1704D01*
G03X136204I-296J-269D01*
G02Y309048I-1704J1548D01*
G03X136796I296J269D01*
G02X140204I1704J-1548D01*
G03X140796I296J269D01*
G02X144048Y305796I1704J-1548D01*
G03Y305204I269J-296D01*
G02Y301796I-1548J-1704D01*
G03Y301204I269J-296D01*
G02X140796Y297952I-1548J-1704D01*
G37*
G36*
G01X94130Y297019D02*
G03Y296481I296J-269D01*
G02X90870I-1630J-1481D01*
G03Y297019I-296J269D01*
G02X94130I1630J1481D01*
G37*
G36*
G01X244796Y292452D02*
G03X244204I-296J-269D01*
G02X240952Y295704I-1704J1548D01*
G03Y296296I-269J296D01*
G02Y299704I1548J1704D01*
G03Y300296I-269J296D01*
G02Y303704I1548J1704D01*
G03Y304296I-269J296D01*
G02X244204Y307548I1548J1704D01*
G03X244796I296J269D01*
G02X248204I1704J-1548D01*
G03X248796I296J269D01*
G02X252048Y304296I1704J-1548D01*
G03Y303704I269J-296D01*
G02Y300296I-1548J-1704D01*
G03Y299704I269J-296D01*
G02Y296296I-1548J-1704D01*
G03Y295704I269J-296D01*
G02X248796Y292452I-1548J-1704D01*
G03X248204I-296J-269D01*
G02X244796I-1704J1548D01*
G37*
G36*
G01X91279Y277688D02*
X77199D01*
X70919Y283967D01*
X70894Y283981D01*
G02X69790Y286646I1106J2019D01*
G01X69798Y286673D01*
Y289327D01*
X69790Y289354D01*
G02X74210I2210J646D01*
G01X74202Y289327D01*
Y286912D01*
X79023Y282090D01*
X89455D01*
X90298Y282934D01*
Y286662D01*
X98048Y294412D01*
Y313200D01*
G02X102452I2202J0D01*
G01Y294412D01*
X105162Y291702D01*
X112912D01*
X114057Y290557D01*
G02X111103Y287298I-1557J-1557D01*
G01X108918D01*
G03X108635Y286616I0J-400D01*
G01X109099Y286152D01*
X123437D01*
G03X123831Y286620I0J400D01*
G02X127184Y288857I2169J380D01*
G03X127798Y289194I214J337D01*
G01Y296298D01*
X124938D01*
X124238Y295598D01*
X119288D01*
X114084Y300802D01*
G03X113401Y300519I-283J-283D01*
G01Y300322D01*
X123013Y290711D01*
G02X119899Y287597I-1557J-1557D01*
G01X110326Y297171D01*
G03X109729Y297136I-283J-283D01*
G02X109630Y297019I-1730J1363D01*
G03Y296481I296J-269D01*
G02X106370I-1630J-1481D01*
G03Y297019I-296J269D01*
G02X106970Y300446I1630J1481D01*
G03Y301154I-187J354D01*
G02X108507Y305243I1030J1946D01*
G03X108998Y305632I91J389D01*
G01Y305947D01*
G03X108353Y306263I-400J0D01*
G02X105370Y309481I-1353J1737D01*
G03Y310019I-296J269D01*
G02X107168Y313696I1630J1481D01*
G03X107598Y314094I30J399D01*
G01Y318314D01*
X105997Y319916D01*
G03X105374Y319843I-283J-283D01*
G02X104909Y319307I-1874J1156D01*
G03Y318693I255J-307D01*
G02X102091I-1409J-1693D01*
G03Y319307I-255J307D01*
G02X101329Y320632I1409J1692D01*
G01X101301Y320798D01*
X89610D01*
X76798Y333610D01*
Y343327D01*
X76790Y343354D01*
G02Y344646I2210J646D01*
G01X76798Y344673D01*
Y347327D01*
X76790Y347354D01*
G02X81210I2210J646D01*
G01X81202Y347327D01*
Y344673D01*
X81210Y344646D01*
G02Y343354I-2210J-646D01*
G01X81202Y343327D01*
Y335434D01*
X91434Y325202D01*
X100062D01*
X101262Y326402D01*
X105738D01*
X112002Y320138D01*
Y314138D01*
X113402Y312738D01*
Y308981D01*
G03X114084Y308698I400J0D01*
G01X117588Y312202D01*
X123086D01*
X124998Y314114D01*
Y315888D01*
X113588Y327298D01*
X98662D01*
X98307Y326943D01*
G02X95193Y330057I-1557J1557D01*
G01X96838Y331702D01*
X115412D01*
X129402Y317712D01*
Y312290D01*
X124910Y307798D01*
X119412D01*
X118999Y307385D01*
X119189Y307195D01*
X119258Y307187D01*
G02X119226Y302810I-258J-2187D01*
G03X118984Y302129I41J-398D01*
G01X121112Y300002D01*
X122414D01*
X123114Y300702D01*
X130000D01*
G02X132202Y298500I0J-2202D01*
G01Y283088D01*
X130057Y280943D01*
G02X128500Y280298I-1557J1557D01*
G01X123964D01*
X122514Y281748D01*
X107275D01*
X104580Y284443D01*
G02X104071Y286760I1557J1556D01*
G03X103696Y287298I-375J138D01*
G01X103338D01*
X102732Y287905D01*
G03X102073Y287757I-283J-283D01*
G02X98057Y287464I-2073J743D01*
G03X97421Y287558I-353J-189D01*
G01X94702Y284838D01*
Y281110D01*
X91279Y277688D01*
G37*
G36*
G01X97307Y276091D02*
G03X96693I-307J-255D01*
G02Y278909I-1693J1409D01*
G03X97307I307J255D01*
G02Y276091I1693J-1409D01*
G37*
G36*
G01X112482Y275620D02*
G03X111867Y275773I-366J-160D01*
G02X108807Y276091I-1367J1727D01*
G03X108193I-307J-255D01*
G02Y278909I-1693J1409D01*
G03X108807I307J255D01*
G02X112518Y278380I1692J-1409D01*
G03X113133Y278227I366J160D01*
G02X115981Y278130I1367J-1727D01*
G03X116519I269J296D01*
G02X119481I1481J-1630D01*
G03X120019I269J296D01*
G02X122752Y278311I1480J-1630D01*
G03X123291Y278388I228J329D01*
G02X123748Y275189I1709J-1388D01*
G03X123209Y275112I-228J-329D01*
G02X120019Y274870I-1709J1388D01*
G03X119481I-269J-296D01*
G02X116519I-1481J1630D01*
G03X115981I-269J-296D01*
G02X112482Y275620I-1481J1630D01*
G37*
G36*
G01X249296Y243452D02*
G03X248704I-296J-269D01*
G02X245725Y246917I-1704J1548D01*
G03Y247583I-221J333D01*
G02X248704Y251048I1275J1917D01*
G03X249296I296J269D01*
G02X252275Y247583I1704J-1548D01*
G03Y246917I221J-333D01*
G02X249296Y243452I-1275J-1917D01*
G37*
G36*
G01Y230952D02*
G03X248704I-296J-269D01*
G02X245452Y234204I-1704J1548D01*
G03Y234796I-269J296D01*
G02X248704Y238048I1548J1704D01*
G03X249296I296J269D01*
G02X252548Y234796I1704J-1548D01*
G03Y234204I269J-296D01*
G02X249296Y230952I-1548J-1704D01*
G37*
G36*
G01X277512Y222821D02*
Y218283D01*
X277505Y218195D01*
G02X272688Y218372I-2405J177D01*
G01Y222812D01*
G02X277512Y222821I2412J-1D01*
G37*
G36*
G01X275512Y211010D02*
Y206472D01*
X275505Y206384D01*
G02X270688Y206561I-2405J177D01*
G01Y211001D01*
G02X275512Y211010I2412J-1D01*
G37*
G36*
G01X264388Y207274D02*
G03X264416Y206687I285J-281D01*
G02X261431Y206545I-1416J-1687D01*
G03X261403Y207132I-285J281D01*
G02X261343Y210453I1416J1687D01*
G03X261371Y211019I-268J297D01*
G02X264476Y210866I1629J1481D01*
G03X264448Y210300I268J-297D01*
G02X264388Y207274I-1629J-1481D01*
G37*
G36*
G01X264630Y192019D02*
G03Y191481I296J-269D01*
G02X261370I-1630J-1481D01*
G03Y192019I-296J269D01*
G02Y194981I1630J1481D01*
G03Y195519I-296J269D01*
G02X264630I1630J1481D01*
G03Y194981I296J-269D01*
G02Y192019I-1630J-1481D01*
G37*
G36*
G01X249296Y175952D02*
G03X248704I-296J-269D01*
G02X245452Y179204I-1704J1548D01*
G03Y179796I-269J296D01*
G02X248704Y183048I1548J1704D01*
G03X249296I296J269D01*
G02X252548Y179796I1704J-1548D01*
G03Y179204I269J-296D01*
G02X249296Y175952I-1548J-1704D01*
G37*
G36*
G01X253630Y153519D02*
G03Y152981I296J-269D01*
G02X250370I-1630J-1481D01*
G03Y153519I-296J269D01*
G02X253630I1630J1481D01*
G37*
G36*
G01X292130Y152769D02*
G03Y152231I296J-269D01*
G02X288870I-1630J-1481D01*
G03Y152769I-296J269D01*
G02X292130I1630J1481D01*
G37*
G36*
G01X249296Y134790D02*
G03X248704I-296J-269D01*
G02X245725Y138255I-1704J1548D01*
G03Y138921I-221J333D01*
G02X248704Y142386I1275J1917D01*
G03X249296I296J269D01*
G02X252275Y138921I1704J-1548D01*
G03Y138255I221J-333D01*
G02X249296Y134790I-1275J-1917D01*
G37*
G36*
G01X294553Y125426D02*
G03X294050Y125195I-131J-378D01*
G02X292643Y128106I-2050J805D01*
G03X293137Y128357I116J383D01*
G02X294553Y125426I2174J-757D01*
G37*
G36*
G01X249296Y122290D02*
G03X248704I-296J-269D01*
G02X245452Y125542I-1704J1548D01*
G03Y126134I-269J296D01*
G02X248704Y129386I1548J1704D01*
G03X249296I296J269D01*
G02X252548Y126134I1704J-1548D01*
G03Y125542I269J-296D01*
G02X249296Y122290I-1548J-1704D01*
G37*
G36*
G01X302938Y126046D02*
G03X303469Y125878I352J190D01*
G02X302433Y122806I1031J-2058D01*
G03X301909Y122994I-359J-176D01*
G02X302938Y126046I-909J2006D01*
G37*
G36*
G01X277512Y114160D02*
Y109621D01*
X277505Y109533D01*
G02X272688Y109710I-2405J177D01*
G01Y114150D01*
G02X277512Y114160I2412J0D01*
G37*
G36*
G01X275512Y102349D02*
Y97810D01*
X275505Y97722D01*
G02X270688Y97899I-2405J177D01*
G01Y102339D01*
G02X275512Y102349I2412J0D01*
G37*
G36*
G01X264458Y98687D02*
G03X264486Y98125I298J-267D01*
G02X261361Y97970I-1486J-1625D01*
G03X261333Y98532I-298J267D01*
G02X261414Y101853I1486J1625D01*
G03X261442Y102444I-255J308D01*
G02X264405Y102304I1558J1556D01*
G03X264377Y101713I255J-308D01*
G02X264458Y98687I-1558J-1556D01*
G37*
G36*
G01X300741Y85540D02*
G02X298934Y85886I-2J4884D01*
G01X298153Y86198D01*
X296953D01*
X296908Y86061D01*
G02X292988Y86699I-1908J638D01*
G01Y89899D01*
G02X296907Y90538I2012J0D01*
G01X296953Y90402D01*
X298275D01*
G02X299598Y90148I-1J-3576D01*
G01X300524Y89779D01*
X300617Y89862D01*
G02X302210Y90483I1613J-1783D01*
G02X302222Y90484I127J-1454D01*
G01X303801D01*
G02X305525Y89744I-11J-2405D01*
G01X311380D01*
G03X311710Y90368I-1J400D01*
G02X311296Y91699I1990J1349D01*
G01Y93290D01*
G02X312036Y95014I2404J-11D01*
G01Y96093D01*
G02X311296Y97809I1664J1735D01*
G01Y99400D01*
G02X312036Y101124I2404J-11D01*
G01Y102203D01*
G02X311296Y103919I1664J1735D01*
G01Y105510D01*
G02X312036Y107234I2404J-11D01*
G01Y108313D01*
G02X311296Y110029I1664J1735D01*
G01Y111620D01*
G02X312036Y113344I2404J-11D01*
G01Y114423D01*
G02X311296Y116139I1664J1735D01*
G01Y117730D01*
G02X312036Y119454I2404J-11D01*
G01Y120533D01*
G02X311296Y122249I1664J1735D01*
G01Y123840D01*
G02X312036Y125564I2404J-11D01*
G01Y126643D01*
G02X311296Y128359I1664J1735D01*
G01Y129950D01*
G02X311979Y131617I2404J-12D01*
G01X312036Y131676D01*
Y132045D01*
G03X311420Y132381I-400J-1D01*
G02X310142Y132002I-1296J2025D01*
G01X308551D01*
G02X306884Y132685I12J2404D01*
G01X306825Y132742D01*
X306500D01*
G03X305208Y132508I2J-3696D01*
G02X300388Y132643I-2408J135D01*
G01Y137043D01*
G02X305211Y136987I2412J0D01*
G03X305600Y136946I385J1785D01*
G01X312297D01*
G02X315085Y135791I-1J-3945D01*
G02X316240Y133003I-2790J-2789D01*
G01Y89117D01*
G02X313950Y85783I-3572J0D01*
G02X313917Y85771I-517J1370D01*
G02X312637Y85539I-1277J3400D01*
G01Y85540D01*
X300741D01*
G37*
G36*
G01X264630Y83357D02*
G03Y82819I296J-269D01*
G02X261370I-1630J-1481D01*
G03Y83357I-296J269D01*
G02X261435Y86388I1630J1481D01*
G03Y86950I-284J281D01*
G02X264565I1565J1550D01*
G03Y86388I284J-281D01*
G02X264630Y83357I-1565J-1550D01*
G37*
G36*
G01X249296Y67290D02*
G03X248704I-296J-269D01*
G02X245452Y70542I-1704J1548D01*
G03Y71134I-269J296D01*
G02X248704Y74386I1548J1704D01*
G03X249296I296J269D01*
G02X252548Y71134I1704J-1548D01*
G03Y70542I269J-296D01*
G02X249296Y67290I-1548J-1704D01*
G37*
G36*
G01X298796Y59452D02*
G03X298204I-296J-269D01*
G02Y62548I-1704J1548D01*
G03X298796I296J269D01*
G02Y59452I1704J-1548D01*
G37*
G36*
G01X301796Y44452D02*
G03X301204I-296J-269D01*
G02X297221Y46327I-1704J1548D01*
G03X296925Y46771I-396J57D01*
G02X295221Y49327I575J2229D01*
G03X294925Y49771I-396J57D01*
G02X297204Y53548I575J2229D01*
G03X297796I296J269D01*
G02X301779Y51673I1704J-1548D01*
G03X302075Y51229I396J-57D01*
G02X303779Y48673I-575J-2229D01*
G03X304075Y48229I396J-57D01*
G02X301796Y44452I-575J-2229D01*
G37*
G36*
G01X173954Y303888D02*
G02X170294Y306609I-1643J1612D01*
G03X169923Y307201I-351J192D01*
G02X168263Y311204I-112J2299D01*
G03Y311796I-269J296D01*
G02X171359I1548J1704D01*
G03Y311204I269J-296D01*
G02X171828Y308391I-1548J-1704D01*
G03X172199Y307799I351J-192D01*
G02X173954Y307112I112J-2299D01*
G03X174525I285J280D01*
G02Y303888I1643J-1612D01*
G03X173954I-286J-280D01*
G37*
G36*
G01X238630Y153981D02*
G02X235370I-1630J-1481D01*
G03Y154519I-296J269D01*
G02X235487Y157599I1630J1480D01*
G03Y158181I-275J291D01*
G02X235468Y161361I1513J1599D01*
G03X235189Y162048I-279J287D01*
G01X229338D01*
X223443Y167943D01*
G02X226557Y171057I1557J1557D01*
G01X231162Y166452D01*
X234487D01*
G03X234796Y167105I0J400D01*
G02X237956Y166848I1704J1395D01*
G03X238032Y166194I264J-301D01*
G02X238127Y162359I-1032J-1944D01*
G03Y161672I205J-343D01*
G02X238513Y158181I-1127J-1891D01*
G03Y157599I275J-291D01*
G02X238630Y154519I-1513J-1600D01*
G03Y153981I296J-269D01*
G37*
G54D22*
X181061Y297750D03*
X195811Y296000D03*
G54D23*
X302000Y290500D03*
Y300500D03*
Y310500D03*
G54D21*
X100500Y347289D03*
X215064Y316100D03*
X251000Y88500D03*
X252000Y160500D03*
X251000Y197000D03*
X263000Y240315D03*
X279000Y166000D03*
X296500Y157500D03*
X291000Y169500D03*
G54D20*
X58000Y310689D03*
X162311Y293000D03*
X160811Y310000D03*
X176311Y294000D03*
X218000Y292000D03*
X215811Y300000D03*
X230000Y96500D03*
X225000Y205000D03*
X222911Y287089D03*
X262920Y131653D03*
X273000Y92283D03*
X295500Y110000D03*
X301711Y245000D03*
G54D17*
X265551Y143464D03*
Y252126D03*
G54D16*
Y64724D03*
Y173386D03*
X311614Y31870D03*
G54D18*
Y185414D03*
G54D19*
X25596Y316176D03*
X237013Y17712D03*
X287407Y345704D03*
%LPD*%
G75*
G54D10*
X25596Y316176D03*
X237013Y17712D03*
X287407Y345704D03*
G54D11*
X10000Y330000D03*
Y345000D03*
Y360000D03*
X40000Y270000D03*
Y285000D03*
Y300000D03*
Y330000D03*
Y345000D03*
X25000Y360000D03*
X40000D03*
X55000Y270000D03*
Y285000D03*
X52500Y325189D03*
Y331189D03*
X55000Y360000D03*
X70000Y270000D03*
X59500Y294189D03*
X72000Y286000D03*
Y290000D03*
X64500Y309589D03*
X59500Y299939D03*
X71500Y315689D03*
X67900D03*
X72000Y336689D03*
X70000Y360000D03*
X85000Y270000D03*
X89000Y295189D03*
Y291189D03*
Y287189D03*
Y283189D03*
Y303689D03*
Y299689D03*
X75100Y315689D03*
X79000Y344000D03*
X89000Y329189D03*
Y333189D03*
X79000Y348000D03*
X85000Y360000D03*
X100000Y270000D03*
Y360000D03*
X115000D03*
X138000Y341500D03*
X130000Y360000D03*
X138000Y345500D03*
X146500Y303500D03*
X150500D03*
X146500Y307500D03*
X150500D03*
X155000Y301350D03*
X149811Y341500D03*
X141811D03*
X145811D03*
X153811D03*
X145000Y360000D03*
X149811Y345500D03*
X141811D03*
X145811D03*
X153811D03*
X164811Y304000D03*
X165811Y341500D03*
X157811D03*
X161811D03*
X169811D03*
X160000Y360000D03*
X165811Y345500D03*
X169811D03*
X157811D03*
X161811D03*
X185811Y304200D03*
Y310500D03*
X181811D03*
Y318500D03*
X185811Y314500D03*
Y326500D03*
Y322500D03*
Y318500D03*
X181811Y326500D03*
Y322500D03*
Y314500D03*
X184500Y334000D03*
Y338000D03*
X175000Y360000D03*
X189811Y310500D03*
Y318500D03*
Y322500D03*
Y326500D03*
Y314500D03*
X190000Y360000D03*
X205000D03*
X220000D03*
X225000Y35000D03*
Y50000D03*
Y80000D03*
Y65000D03*
X230000Y75000D03*
Y67000D03*
Y71000D03*
X225000Y95000D03*
Y110000D03*
X230000Y126000D03*
Y130000D03*
Y122000D03*
Y138500D03*
Y142500D03*
Y134500D03*
Y175500D03*
Y179500D03*
Y183500D03*
Y243000D03*
Y234500D03*
Y238500D03*
Y230500D03*
Y247000D03*
Y251000D03*
X237500Y340000D03*
Y344000D03*
Y336000D03*
X235000Y360000D03*
X255000Y5000D03*
Y35000D03*
X249000Y260000D03*
X241500Y336000D03*
Y344000D03*
Y340000D03*
X250000Y360000D03*
X270000Y5000D03*
Y35000D03*
X265000Y270000D03*
Y285000D03*
X271500Y294000D03*
X267500D03*
X271500Y306000D03*
Y302000D03*
Y298000D03*
X267500D03*
Y302000D03*
Y306000D03*
X260500Y340000D03*
Y344000D03*
Y336000D03*
X256500D03*
Y344000D03*
Y340000D03*
X265000Y360000D03*
X282500Y5000D03*
X272500Y20000D03*
X285000Y32500D03*
X275500Y63346D03*
X280000Y71614D03*
Y67677D03*
X280169Y126732D03*
Y120826D03*
X275768Y144842D03*
X280169Y138543D03*
Y132637D03*
X280000Y176339D03*
X275500Y172008D03*
X280000Y180276D03*
X280169Y247205D03*
X275768Y253504D03*
X280000Y270000D03*
X275500Y294000D03*
X280000Y285000D03*
X275500Y298000D03*
Y302000D03*
Y306000D03*
X280000Y300000D03*
Y315000D03*
X295000Y5000D03*
X300000Y20000D03*
Y35000D03*
X304565Y61142D03*
Y96142D03*
X304500Y92000D03*
X291500Y97204D03*
X291550Y91299D03*
X291500Y85393D03*
X295500Y100000D03*
X291500Y109960D03*
Y101960D03*
Y114921D03*
X304565Y141142D03*
X295500Y208461D03*
X291500Y210961D03*
Y205866D03*
Y218461D03*
Y223583D03*
Y241299D03*
Y229488D03*
Y235394D03*
X295000Y270000D03*
Y285000D03*
Y300000D03*
Y315000D03*
X315000Y5000D03*
Y20000D03*
Y40000D03*
X313000Y179500D03*
X310000Y225000D03*
Y240000D03*
Y255000D03*
Y270000D03*
Y285000D03*
Y300000D03*
Y315000D03*
Y330000D03*
Y360000D03*
Y345000D03*
X324302Y203977D03*
X325000Y225000D03*
Y240000D03*
Y255000D03*
Y270000D03*
Y285000D03*
Y300000D03*
Y315000D03*
Y330000D03*
Y360000D03*
Y345000D03*
X345000Y5000D03*
Y20000D03*
X340000Y285000D03*
Y300000D03*
Y315000D03*
Y330000D03*
Y360000D03*
Y345000D03*
G54D12*
G01X-176139Y-183003D02*
G02I-12000J0D01*
G01X-181289D02*
G02I-6850J0D01*
G01X-172139D02*
X-204139D01*
G01X-188139Y-199003D02*
Y-167003D01*
G01X-172139Y-199003D02*
Y-279003D01*
G01D02*
X1178561D01*
G01X-172139Y-234503D02*
X1178561D01*
G01X-172139Y-199003D02*
X1178561D01*
G01X16394Y316176D02*
X25596D01*
G01Y306974D02*
Y316176D01*
G01D02*
Y325378D01*
G01Y316176D02*
X34798D01*
G01X72000Y286000D02*
X78111Y279889D01*
X90367D01*
X92500Y282022D01*
Y285750D01*
X100250Y293500D01*
G01X72000Y290000D02*
Y286000D01*
G01X121456Y289154D02*
X111200Y299410D01*
Y311826D01*
X109800Y313226D01*
Y319226D01*
X104826Y324200D01*
X102174D01*
X100974Y323000D01*
X90522D01*
X79000Y334522D01*
Y344000D01*
G01D02*
Y348000D01*
G01X100250Y313200D02*
Y293500D01*
G01X112500Y289000D02*
X112000Y289500D01*
X104250D01*
X100250Y293500D01*
G01X128500Y282500D02*
X124876D01*
X123426Y283950D01*
X108187D01*
X106137Y286000D01*
G01X115000Y305000D02*
Y306500D01*
X118500Y310000D01*
X123998D01*
X127200Y313202D01*
Y316800D01*
X114500Y329500D01*
X97750D01*
X96750Y328500D01*
G01X115000Y305000D02*
Y303000D01*
X120200Y297800D01*
X123326D01*
X124026Y298500D01*
X130000D01*
G01X128500Y282500D02*
X130000Y284000D01*
Y298500D01*
G01X237013Y8510D02*
Y17712D01*
G01D02*
Y26914D01*
G01X227811Y17712D02*
X237013D01*
G01D02*
X246215D01*
G01X237000Y164250D02*
X230250D01*
X225000Y169500D01*
G01X268140Y161221D02*
X265529D01*
X258750Y168000D01*
G01X287407Y336502D02*
Y345704D01*
G01D02*
Y354906D01*
G01X278205Y345704D02*
X287407D01*
G01D02*
X296609D01*
G01X302000Y306298D02*
Y310500D01*
G01D02*
Y314702D01*
G01X297798Y310500D02*
X302000D01*
G01D02*
X306202D01*
G01X391061Y-199003D02*
Y-279003D01*
G01X528561Y-199003D02*
Y-279003D01*
G01X643561Y-199003D02*
Y-279003D01*
G01X811061Y-199003D02*
Y-279003D01*
G01X981061Y-199003D02*
Y-279003D01*
G01X1178561Y-199003D02*
Y-279003D01*
G01X1210561Y-183003D02*
X1178561D01*
G01X1206561D02*
G02I-12000J0D01*
G01X1201411D02*
G02I-6850J0D01*
G01X1194561Y-199003D02*
Y-167003D01*
X103000Y277500D03*
X106137Y286000D03*
X96750Y313250D03*
X103750Y313200D03*
X100250D03*
X100500Y335689D03*
X96750Y328500D03*
X121456Y289154D03*
X122100Y280750D03*
X112500Y289000D03*
X122000Y301000D03*
X115000Y305000D03*
X128500Y282500D03*
X130000Y298500D03*
X124000Y315000D03*
X140500Y281000D03*
X236805Y146452D03*
X225000Y160250D03*
Y149250D03*
Y164250D03*
Y169500D03*
X237000Y164250D03*
X251500Y164500D03*
X269650Y97899D03*
X271650Y109710D03*
X269650Y102299D03*
X271650Y114110D03*
X271250Y138750D03*
X267700Y153250D03*
X268140Y161221D03*
X258750Y168000D03*
X269650Y210961D03*
Y206561D03*
X271650Y222772D03*
Y218372D03*
X278860Y162250D03*
X273500Y194055D03*
Y199961D03*
X273600Y240250D03*
X295000Y86699D03*
Y89899D03*
X300500Y129100D03*
X299300Y137043D03*
Y132643D03*
X302800Y137043D03*
Y132643D03*
X302000Y157500D03*
X292000Y181500D03*
X294750Y195261D03*
X291300Y195361D03*
X294750Y198661D03*
X291300Y198561D03*
X325244Y56201D03*
Y75099D03*
Y65650D03*
Y93996D03*
Y84548D03*
Y112894D03*
Y103445D03*
Y128642D03*
Y119193D03*
Y144390D03*
Y138091D03*
Y153839D03*
Y163288D03*
Y166437D03*
Y169587D03*
G54D13*
X302000Y310500D03*
G54D14*
G01X-148956Y-251503D02*
Y-269003D01*
X-140222D01*
G01X-127089Y-257337D02*
Y-269003D01*
G01Y-252670D02*
X-127526Y-252378D01*
Y-251795D01*
X-127089Y-251503D01*
X-126652Y-251795D01*
Y-252378D01*
X-127089Y-252670D01*
G01X-112646Y-273378D02*
X-111117Y-274545D01*
X-109371Y-274836D01*
X-107843Y-274545D01*
X-106532Y-273087D01*
X-105659Y-271045D01*
Y-257337D01*
G01Y-259670D02*
X-106532Y-258503D01*
X-107843Y-257628D01*
X-109371Y-257337D01*
X-111117Y-257920D01*
X-112209Y-259086D01*
X-113083Y-261128D01*
X-113519Y-263170D01*
X-113301Y-264920D01*
X-112427Y-266962D01*
X-111117Y-268420D01*
X-109371Y-269003D01*
X-108061Y-268711D01*
X-106532Y-267545D01*
X-105659Y-266379D01*
G01X-95801Y-269003D02*
Y-251503D01*
G01Y-259961D02*
X-94709Y-258503D01*
X-93617Y-257628D01*
X-91871Y-257337D01*
X-90561Y-257628D01*
X-89032Y-258795D01*
X-88377Y-260545D01*
Y-269003D01*
G01X-74589Y-251503D02*
Y-269003D01*
G01X-77646Y-257337D02*
X-71532D01*
G01X-60801Y-269003D02*
Y-257337D01*
G01Y-260253D02*
X-59927Y-258795D01*
X-58617Y-257628D01*
X-56871Y-257337D01*
X-55343Y-257628D01*
X-54032Y-258795D01*
X-53377Y-260836D01*
Y-269003D01*
G01X-39589Y-257337D02*
Y-269003D01*
G01Y-252670D02*
X-40026Y-252378D01*
Y-251795D01*
X-39589Y-251503D01*
X-39152Y-251795D01*
Y-252378D01*
X-39589Y-252670D01*
G01X-25801Y-269003D02*
Y-257337D01*
G01Y-260253D02*
X-24927Y-258795D01*
X-23617Y-257628D01*
X-21871Y-257337D01*
X-20343Y-257628D01*
X-19032Y-258795D01*
X-18377Y-260836D01*
Y-269003D01*
G01X-7646Y-273378D02*
X-6117Y-274545D01*
X-4371Y-274836D01*
X-2843Y-274545D01*
X-1532Y-273087D01*
X-659Y-271045D01*
Y-257337D01*
G01Y-259670D02*
X-1532Y-258503D01*
X-2843Y-257628D01*
X-4371Y-257337D01*
X-6117Y-257920D01*
X-7209Y-259086D01*
X-8083Y-261128D01*
X-8519Y-263170D01*
X-8301Y-264920D01*
X-7427Y-266962D01*
X-6117Y-268420D01*
X-4371Y-269003D01*
X-3061Y-268711D01*
X-1532Y-267545D01*
X-659Y-266379D01*
G01X26044Y-269003D02*
Y-251503D01*
X31284D01*
X33031Y-252378D01*
X34341Y-254420D01*
X34778Y-256753D01*
X34341Y-259086D01*
X33249Y-260836D01*
X31284Y-261712D01*
X26044D01*
G01X42452Y-251503D02*
X47911Y-269003D01*
X53370Y-251503D01*
G01X65411D02*
Y-269003D01*
G01X60389Y-251503D02*
X70433D01*
G01X94734Y-269003D02*
Y-251503D01*
X100411Y-266086D01*
X106088Y-251503D01*
Y-269003D01*
G01X117911Y-269586D02*
X117474Y-269295D01*
Y-268711D01*
X117911Y-268420D01*
X118348Y-268711D01*
Y-269295D01*
X117911Y-269586D01*
G01X131263Y-254420D02*
X132573Y-252670D01*
X134101Y-251795D01*
X135848Y-251503D01*
X138031Y-252086D01*
X139559Y-253545D01*
X139996Y-255294D01*
X139778Y-257045D01*
X138904Y-258503D01*
X134538Y-261420D01*
X132573Y-263461D01*
X131263Y-266379D01*
X130826Y-269003D01*
X139996D01*
G01X164952D02*
X170411Y-251503D01*
X175870Y-269003D01*
G01X173904Y-262878D02*
X166917D01*
G01X191841Y-251503D02*
Y-269003D01*
G01Y-266379D02*
X190968Y-267837D01*
X189657Y-268711D01*
X188129Y-269003D01*
X186383Y-268420D01*
X185073Y-266962D01*
X184199Y-265212D01*
X183981Y-263170D01*
X184199Y-261128D01*
X185073Y-259378D01*
X186383Y-257920D01*
X188129Y-257337D01*
X189657Y-257628D01*
X190749Y-258212D01*
X191841Y-259378D01*
G01X209341Y-269003D02*
Y-257337D01*
G01Y-259378D02*
X208468Y-258212D01*
X207157Y-257628D01*
X205629Y-257337D01*
X204101Y-257920D01*
X202791Y-259086D01*
X201917Y-260836D01*
X201481Y-263170D01*
X201917Y-265503D01*
X202791Y-267253D01*
X204101Y-268420D01*
X205629Y-269003D01*
X207157Y-268711D01*
X208468Y-267837D01*
X209341Y-266670D01*
G01X218981Y-274836D02*
Y-257337D01*
G01Y-259961D02*
X220073Y-258503D01*
X221164Y-257628D01*
X222911Y-257337D01*
X224439Y-257628D01*
X225968Y-259086D01*
X226623Y-261128D01*
X226841Y-263170D01*
X226623Y-265212D01*
X225968Y-267253D01*
X224657Y-268420D01*
X222911Y-269003D01*
X221383Y-268711D01*
X219854Y-267837D01*
X218981Y-266670D01*
G01X240411Y-251503D02*
Y-269003D01*
G01X237354Y-257337D02*
X243468D01*
G01X257911Y-269003D02*
X256601Y-268711D01*
X255291Y-267545D01*
X254417Y-265503D01*
X253981Y-263170D01*
X254417Y-260836D01*
X255291Y-258795D01*
X256601Y-257628D01*
X257911Y-257337D01*
X259221Y-257628D01*
X260531Y-258795D01*
X261404Y-260836D01*
X261623Y-263170D01*
X261404Y-265503D01*
X260531Y-267545D01*
X259221Y-268711D01*
X257911Y-269003D01*
G01X272354D02*
Y-257337D01*
G01Y-259670D02*
X273446Y-258503D01*
X274538Y-257628D01*
X276066Y-257337D01*
X277157Y-257628D01*
X278468Y-258503D01*
G01X315214Y-252962D02*
X313904Y-252086D01*
X312376Y-251503D01*
X310629D01*
X308664Y-252378D01*
X307136Y-253836D01*
X306044Y-255587D01*
X305171Y-258503D01*
X304952Y-261128D01*
X305389Y-263753D01*
X306044Y-265503D01*
X307354Y-267253D01*
X308883Y-268420D01*
X310411Y-269003D01*
X311939D01*
X313468Y-268420D01*
X314778Y-267545D01*
X315870Y-266379D01*
G01X331841Y-269003D02*
Y-257337D01*
G01Y-259378D02*
X330968Y-258212D01*
X329657Y-257628D01*
X328129Y-257337D01*
X326601Y-257920D01*
X325291Y-259086D01*
X324417Y-260836D01*
X323981Y-263170D01*
X324417Y-265503D01*
X325291Y-267253D01*
X326601Y-268420D01*
X328129Y-269003D01*
X329657Y-268711D01*
X330968Y-267837D01*
X331841Y-266670D01*
G01X342354Y-269003D02*
Y-257337D01*
G01Y-259670D02*
X343446Y-258503D01*
X344538Y-257628D01*
X346066Y-257337D01*
X347157Y-257628D01*
X348468Y-258503D01*
G01X366841Y-251503D02*
Y-269003D01*
G01Y-266379D02*
X365968Y-267837D01*
X364657Y-268711D01*
X363129Y-269003D01*
X361383Y-268420D01*
X360073Y-266962D01*
X359199Y-265212D01*
X358981Y-263170D01*
X359199Y-261128D01*
X360073Y-259378D01*
X361383Y-257920D01*
X363129Y-257337D01*
X364657Y-257628D01*
X365749Y-258212D01*
X366841Y-259378D01*
G01X68484Y-224003D02*
Y-206503D01*
X74161Y-221086D01*
X79838Y-206503D01*
Y-224003D01*
G01X91661D02*
X90351Y-223711D01*
X89041Y-222545D01*
X88167Y-220503D01*
X87731Y-218170D01*
X88167Y-215836D01*
X89041Y-213795D01*
X90351Y-212628D01*
X91661Y-212337D01*
X92971Y-212628D01*
X94281Y-213795D01*
X95154Y-215836D01*
X95373Y-218170D01*
X95154Y-220503D01*
X94281Y-222545D01*
X92971Y-223711D01*
X91661Y-224003D01*
G01X113091Y-206503D02*
Y-224003D01*
G01Y-221379D02*
X112218Y-222837D01*
X110907Y-223711D01*
X109379Y-224003D01*
X107633Y-223420D01*
X106323Y-221962D01*
X105449Y-220212D01*
X105231Y-218170D01*
X105449Y-216128D01*
X106323Y-214378D01*
X107633Y-212920D01*
X109379Y-212337D01*
X110907Y-212628D01*
X111999Y-213212D01*
X113091Y-214378D01*
G01X123386Y-216128D02*
X130373D01*
X129718Y-214086D01*
X128626Y-212920D01*
X127098Y-212337D01*
X125569Y-212628D01*
X124259Y-213503D01*
X123386Y-215545D01*
X122949Y-217295D01*
Y-219045D01*
X123386Y-220795D01*
X124478Y-222545D01*
X125788Y-223711D01*
X127316Y-224003D01*
X128844Y-223420D01*
X130373Y-221670D01*
G01X144161Y-224003D02*
Y-206503D01*
G01X424761Y-269003D02*
Y-251503D01*
X422141Y-255003D01*
G01Y-269003D02*
X427381D01*
G01X437458Y-266379D02*
X438767Y-267837D01*
X440296Y-268711D01*
X442261Y-269003D01*
X444226Y-268420D01*
X445754Y-267253D01*
X446846Y-265212D01*
X447064Y-262878D01*
X446628Y-260545D01*
X445536Y-259086D01*
X444007Y-257920D01*
X442479Y-257628D01*
X440951Y-257920D01*
X438986Y-259086D01*
X439641Y-251503D01*
X445536D01*
G01X459324Y-269003D02*
X459761Y-265212D01*
X460416Y-262003D01*
X461289Y-259086D01*
X462381Y-255878D01*
X464128Y-251503D01*
X455394D01*
G01X472458Y-266379D02*
X473767Y-267837D01*
X475296Y-268711D01*
X477261Y-269003D01*
X479226Y-268420D01*
X480754Y-267253D01*
X481846Y-265212D01*
X482064Y-262878D01*
X481628Y-260545D01*
X480536Y-259086D01*
X479007Y-257920D01*
X477479Y-257628D01*
X475951Y-257920D01*
X473986Y-259086D01*
X474641Y-251503D01*
X480536D01*
G01X494761D02*
X493014Y-252086D01*
X491704Y-253545D01*
X490831Y-255294D01*
X490176Y-257628D01*
X489958Y-260253D01*
X490176Y-262878D01*
X490831Y-265212D01*
X491704Y-266962D01*
X493014Y-268420D01*
X494761Y-269003D01*
X496507Y-268420D01*
X497818Y-266962D01*
X498691Y-265212D01*
X499346Y-262878D01*
X499564Y-260253D01*
X499346Y-257628D01*
X498691Y-255294D01*
X497818Y-253545D01*
X496507Y-252086D01*
X494761Y-251503D01*
G01X411644Y-224003D02*
Y-206503D01*
X416884D01*
X418631Y-207378D01*
X419941Y-209420D01*
X420378Y-211753D01*
X419941Y-214086D01*
X418849Y-215836D01*
X416884Y-216712D01*
X411644D01*
G01X438314Y-207962D02*
X437004Y-207086D01*
X435476Y-206503D01*
X433729D01*
X431764Y-207378D01*
X430236Y-208836D01*
X429144Y-210587D01*
X428271Y-213503D01*
X428052Y-216128D01*
X428489Y-218753D01*
X429144Y-220503D01*
X430454Y-222253D01*
X431983Y-223420D01*
X433511Y-224003D01*
X435039D01*
X436568Y-223420D01*
X437878Y-222545D01*
X438970Y-221379D01*
G01X452757Y-214670D02*
X453631Y-213795D01*
X454286Y-212337D01*
X454723Y-210294D01*
X454286Y-208545D01*
X453413Y-207378D01*
X451884Y-206503D01*
X445989D01*
Y-224003D01*
X453194D01*
X454723Y-222837D01*
X455596Y-221086D01*
X456033Y-219045D01*
X455596Y-217003D01*
X454286Y-215253D01*
X452757Y-214670D01*
X445989D01*
G01X461961Y-229836D02*
X475061D01*
G01X480989Y-224003D02*
Y-206503D01*
X491033Y-224003D01*
Y-206503D01*
G01X503511Y-224003D02*
X501764Y-223711D01*
X500236Y-222545D01*
X498926Y-220795D01*
X498052Y-218753D01*
X497616Y-216420D01*
Y-214086D01*
X498052Y-211753D01*
X498926Y-209711D01*
X500236Y-207962D01*
X501764Y-206795D01*
X503511Y-206503D01*
X505257Y-206795D01*
X506786Y-207962D01*
X508096Y-209711D01*
X508970Y-211753D01*
X509406Y-214086D01*
Y-216420D01*
X508970Y-218753D01*
X508096Y-220795D01*
X506786Y-222545D01*
X505257Y-223711D01*
X503511Y-224003D01*
G01X554352Y-206503D02*
X559811Y-224003D01*
X565270Y-206503D01*
G01X581678Y-224003D02*
X572944D01*
Y-206503D01*
X581678D01*
G01X578184Y-214961D02*
X572944D01*
G01X590444Y-224003D02*
Y-206503D01*
X595903D01*
X597649Y-207378D01*
X598741Y-208545D01*
X599178Y-210878D01*
X598741Y-213212D01*
X597431Y-214670D01*
X595903Y-215545D01*
X590444D01*
G01X595903D02*
X599178Y-224003D01*
G01X612311Y-224586D02*
X611874Y-224295D01*
Y-223711D01*
X612311Y-223420D01*
X612748Y-223711D01*
Y-224295D01*
X612311Y-224586D01*
G01X586061Y-269003D02*
Y-251503D01*
X583441Y-255003D01*
G01Y-269003D02*
X588681D01*
G01X687894Y-206503D02*
Y-224003D01*
X696628D01*
G01X713691D02*
Y-212337D01*
G01Y-214378D02*
X712818Y-213212D01*
X711507Y-212628D01*
X709979Y-212337D01*
X708451Y-212920D01*
X707141Y-214086D01*
X706267Y-215836D01*
X705831Y-218170D01*
X706267Y-220503D01*
X707141Y-222253D01*
X708451Y-223420D01*
X709979Y-224003D01*
X711507Y-223711D01*
X712818Y-222837D01*
X713691Y-221670D01*
G01X722676Y-229253D02*
X723986Y-229836D01*
X725733Y-229253D01*
X726824Y-228087D01*
X727698Y-226628D01*
X729007Y-221962D01*
X731846Y-212337D01*
G01X724859D02*
X729007Y-221962D01*
G01X741486Y-216128D02*
X748473D01*
X747818Y-214086D01*
X746726Y-212920D01*
X745198Y-212337D01*
X743669Y-212628D01*
X742359Y-213503D01*
X741486Y-215545D01*
X741049Y-217295D01*
Y-219045D01*
X741486Y-220795D01*
X742578Y-222545D01*
X743888Y-223711D01*
X745416Y-224003D01*
X746944Y-223420D01*
X748473Y-221670D01*
G01X759204Y-224003D02*
Y-212337D01*
G01Y-214670D02*
X760296Y-213503D01*
X761388Y-212628D01*
X762916Y-212337D01*
X764007Y-212628D01*
X765318Y-213503D01*
G01X740378Y-251503D02*
Y-269003D01*
X731644D01*
G01X722659Y-261712D02*
X721131Y-259670D01*
X719821Y-258503D01*
X718074Y-257920D01*
X716546Y-258503D01*
X715454Y-259670D01*
X714581Y-261420D01*
X714363Y-263461D01*
X714581Y-265212D01*
X715454Y-266962D01*
X716765Y-268420D01*
X718293Y-269003D01*
X720039Y-268420D01*
X721568Y-266670D01*
X722441Y-264045D01*
X722659Y-261128D01*
X722223Y-257337D01*
X721568Y-255294D01*
X720476Y-253253D01*
X718948Y-251795D01*
X717419Y-251503D01*
X715891Y-252086D01*
X714799Y-253545D01*
G01X830008Y-224003D02*
Y-206503D01*
X834374D01*
X836121Y-207378D01*
X837431Y-208545D01*
X838523Y-210294D01*
X839396Y-212337D01*
X839614Y-215253D01*
X839396Y-218170D01*
X838523Y-220212D01*
X837431Y-221962D01*
X836121Y-223128D01*
X834374Y-224003D01*
X830008D01*
G01X849036Y-216128D02*
X856023D01*
X855368Y-214086D01*
X854276Y-212920D01*
X852748Y-212337D01*
X851219Y-212628D01*
X849909Y-213503D01*
X849036Y-215545D01*
X848599Y-217295D01*
Y-219045D01*
X849036Y-220795D01*
X850128Y-222545D01*
X851438Y-223711D01*
X852966Y-224003D01*
X854494Y-223420D01*
X856023Y-221670D01*
G01X866536Y-221962D02*
X867628Y-223128D01*
X869156Y-224003D01*
X870466D01*
X871776Y-223420D01*
X872649Y-222545D01*
X873086Y-221379D01*
X872868Y-219628D01*
X871994Y-218753D01*
X868064Y-217003D01*
X867191Y-214961D01*
X867628Y-213503D01*
X868501Y-212628D01*
X869811Y-212337D01*
X871121Y-212628D01*
X872431Y-213503D01*
G01X887311Y-212337D02*
Y-224003D01*
G01Y-207670D02*
X886874Y-207378D01*
Y-206795D01*
X887311Y-206503D01*
X887748Y-206795D01*
Y-207378D01*
X887311Y-207670D01*
G01X901754Y-228378D02*
X903283Y-229545D01*
X905029Y-229836D01*
X906557Y-229545D01*
X907868Y-228087D01*
X908741Y-226045D01*
Y-212337D01*
G01Y-214670D02*
X907868Y-213503D01*
X906557Y-212628D01*
X905029Y-212337D01*
X903283Y-212920D01*
X902191Y-214086D01*
X901317Y-216128D01*
X900881Y-218170D01*
X901099Y-219920D01*
X901973Y-221962D01*
X903283Y-223420D01*
X905029Y-224003D01*
X906339Y-223711D01*
X907868Y-222545D01*
X908741Y-221379D01*
G01X918599Y-224003D02*
Y-212337D01*
G01Y-215253D02*
X919473Y-213795D01*
X920783Y-212628D01*
X922529Y-212337D01*
X924057Y-212628D01*
X925368Y-213795D01*
X926023Y-215836D01*
Y-224003D01*
G01X936536Y-216128D02*
X943523D01*
X942868Y-214086D01*
X941776Y-212920D01*
X940248Y-212337D01*
X938719Y-212628D01*
X937409Y-213503D01*
X936536Y-215545D01*
X936099Y-217295D01*
Y-219045D01*
X936536Y-220795D01*
X937628Y-222545D01*
X938938Y-223711D01*
X940466Y-224003D01*
X941994Y-223420D01*
X943523Y-221670D01*
G01X954254Y-224003D02*
Y-212337D01*
G01Y-214670D02*
X955346Y-213503D01*
X956438Y-212628D01*
X957966Y-212337D01*
X959057Y-212628D01*
X960368Y-213503D01*
G01X874194Y-265503D02*
X875286Y-267253D01*
X876596Y-268420D01*
X878124Y-269003D01*
X879871Y-268420D01*
X881181Y-267253D01*
X882491Y-265503D01*
X882928Y-263170D01*
Y-251503D01*
G01X896061Y-269003D02*
X894314Y-268711D01*
X892786Y-267545D01*
X891476Y-265795D01*
X890602Y-263753D01*
X890166Y-261420D01*
Y-259086D01*
X890602Y-256753D01*
X891476Y-254711D01*
X892786Y-252962D01*
X894314Y-251795D01*
X896061Y-251503D01*
X897807Y-251795D01*
X899336Y-252962D01*
X900646Y-254711D01*
X901520Y-256753D01*
X901956Y-259086D01*
Y-261420D01*
X901520Y-263753D01*
X900646Y-265795D01*
X899336Y-267545D01*
X897807Y-268711D01*
X896061Y-269003D01*
G01X913561D02*
Y-261128D01*
X909194Y-251503D01*
G01X917928D02*
X913561Y-261128D01*
G01X1001011Y-269003D02*
Y-251503D01*
X998391Y-255003D01*
G01Y-269003D02*
X1003631D01*
G01X1014363Y-254420D02*
X1015673Y-252670D01*
X1017201Y-251795D01*
X1018948Y-251503D01*
X1021131Y-252086D01*
X1022659Y-253545D01*
X1023096Y-255294D01*
X1022878Y-257045D01*
X1022004Y-258503D01*
X1017638Y-261420D01*
X1015673Y-263461D01*
X1014363Y-266379D01*
X1013926Y-269003D01*
X1023096D01*
G01X1032081Y-269586D02*
X1039941Y-251503D01*
G01X1048708Y-265503D02*
X1050017Y-267545D01*
X1051764Y-268711D01*
X1053729Y-269003D01*
X1055476Y-268711D01*
X1057223Y-267253D01*
X1058314Y-265503D01*
X1058533Y-263753D01*
X1058096Y-261712D01*
X1056568Y-260253D01*
X1055039Y-259670D01*
X1053074D01*
G01X1055039D02*
X1056349Y-258795D01*
X1057441Y-257337D01*
X1057878Y-255587D01*
X1057441Y-253836D01*
X1056349Y-252378D01*
X1054384Y-251503D01*
X1052419Y-251795D01*
X1050454Y-252962D01*
G01X1071011Y-251503D02*
X1069264Y-252086D01*
X1067954Y-253545D01*
X1067081Y-255294D01*
X1066426Y-257628D01*
X1066208Y-260253D01*
X1066426Y-262878D01*
X1067081Y-265212D01*
X1067954Y-266962D01*
X1069264Y-268420D01*
X1071011Y-269003D01*
X1072757Y-268420D01*
X1074068Y-266962D01*
X1074941Y-265212D01*
X1075596Y-262878D01*
X1075814Y-260253D01*
X1075596Y-257628D01*
X1074941Y-255294D01*
X1074068Y-253545D01*
X1072757Y-252086D01*
X1071011Y-251503D01*
G01X1084581Y-269586D02*
X1092441Y-251503D01*
G01X1101863Y-254420D02*
X1103173Y-252670D01*
X1104701Y-251795D01*
X1106448Y-251503D01*
X1108631Y-252086D01*
X1110159Y-253545D01*
X1110596Y-255294D01*
X1110378Y-257045D01*
X1109504Y-258503D01*
X1105138Y-261420D01*
X1103173Y-263461D01*
X1101863Y-266379D01*
X1101426Y-269003D01*
X1110596D01*
G01X1123511Y-251503D02*
X1121764Y-252086D01*
X1120454Y-253545D01*
X1119581Y-255294D01*
X1118926Y-257628D01*
X1118708Y-260253D01*
X1118926Y-262878D01*
X1119581Y-265212D01*
X1120454Y-266962D01*
X1121764Y-268420D01*
X1123511Y-269003D01*
X1125257Y-268420D01*
X1126568Y-266962D01*
X1127441Y-265212D01*
X1128096Y-262878D01*
X1128314Y-260253D01*
X1128096Y-257628D01*
X1127441Y-255294D01*
X1126568Y-253545D01*
X1125257Y-252086D01*
X1123511Y-251503D01*
G01X1141011Y-269003D02*
Y-251503D01*
X1138391Y-255003D01*
G01Y-269003D02*
X1143631D01*
G01X1154363Y-261712D02*
X1155891Y-259670D01*
X1157201Y-258503D01*
X1158948Y-257920D01*
X1160476Y-258503D01*
X1161568Y-259670D01*
X1162441Y-261420D01*
X1162659Y-263461D01*
X1162441Y-265212D01*
X1161568Y-266962D01*
X1160257Y-268420D01*
X1158729Y-269003D01*
X1156983Y-268420D01*
X1155454Y-266670D01*
X1154581Y-264045D01*
X1154363Y-261128D01*
X1154799Y-257337D01*
X1155454Y-255294D01*
X1156546Y-253253D01*
X1158074Y-251795D01*
X1159603Y-251503D01*
X1161131Y-252086D01*
X1162223Y-253545D01*
G01X1048708Y-224003D02*
Y-206503D01*
X1053074D01*
X1054821Y-207378D01*
X1056131Y-208545D01*
X1057223Y-210294D01*
X1058096Y-212337D01*
X1058314Y-215253D01*
X1058096Y-218170D01*
X1057223Y-220212D01*
X1056131Y-221962D01*
X1054821Y-223128D01*
X1053074Y-224003D01*
X1048708D01*
G01X1074941D02*
Y-212337D01*
G01Y-214378D02*
X1074068Y-213212D01*
X1072757Y-212628D01*
X1071229Y-212337D01*
X1069701Y-212920D01*
X1068391Y-214086D01*
X1067517Y-215836D01*
X1067081Y-218170D01*
X1067517Y-220503D01*
X1068391Y-222253D01*
X1069701Y-223420D01*
X1071229Y-224003D01*
X1072757Y-223711D01*
X1074068Y-222837D01*
X1074941Y-221670D01*
G01X1088511Y-206503D02*
Y-224003D01*
G01X1085454Y-212337D02*
X1091568D01*
G01X1102736Y-216128D02*
X1109723D01*
X1109068Y-214086D01*
X1107976Y-212920D01*
X1106448Y-212337D01*
X1104919Y-212628D01*
X1103609Y-213503D01*
X1102736Y-215545D01*
X1102299Y-217295D01*
Y-219045D01*
X1102736Y-220795D01*
X1103828Y-222545D01*
X1105138Y-223711D01*
X1106666Y-224003D01*
X1108194Y-223420D01*
X1109723Y-221670D01*
G54D15*
G01X291300Y198561D02*
G02X287500Y197556I-3800J6682D01*
G01X287184D01*
G03X285593Y196897I0J-2250D01*
G01X285530Y196834D01*
G03X284725Y194889I1945J-1944D01*
G01Y183372D01*
G03X285715Y180981I3381J-1D01*
G01X291906Y174790D01*
X298098Y168597D01*
X298526Y168170D01*
G03X300453Y167375I1925J1934D01*
G01X322000D01*
G02X325244Y166437I0J-6079D01*
G01X291300Y195361D02*
G03X288200Y196281I-3100J-4763D01*
G01X287275D01*
G03X286432Y195932I0J-1192D01*
G03X286000Y194889I1043J-1043D01*
G03X286370Y194149I940J7D01*
G02X286740Y193409I-570J-747D01*
G01Y191834D01*
G02X286370Y191094I-940J7D01*
G03X286000Y190354I570J-747D01*
G01Y188779D01*
G03X286370Y188039I940J7D01*
G02X286740Y187299I-570J-747D01*
G01Y185724D01*
G02X286370Y184984I-940J7D01*
G03X286000Y184244I570J-747D01*
G01Y183372D01*
G03X286617Y181883I2105J0D01*
G01X287152Y181348D01*
G03X287937Y181086I660J670D01*
G02X288722Y180824I125J-932D01*
G01X289836Y179711D01*
G02X290097Y178926I-671J-659D01*
G03X290359Y178141I932J-125D01*
G01X291473Y177027D01*
G03X292257Y176766I659J670D01*
G02X293042Y176504I125J-932D01*
G01X294156Y175390D01*
G02X294418Y174605I-670J-660D01*
G03X294679Y173821I931J-125D01*
G01X295793Y172707D01*
G03X296578Y172445I660J670D01*
G02X297363Y172184I126J-932D01*
G01X298476Y171070D01*
G02X298738Y170285I-670J-660D01*
G03X299000Y169500I932J-125D01*
G01X299427Y169074D01*
G03X300453Y168650I1026J1029D01*
G01X304170D01*
G03X304910Y169020I-7J940D01*
G02X305650Y169390I747J-570D01*
G01X307225D01*
G02X307965Y169020I-7J-940D01*
G03X308705Y168650I747J570D01*
G01X310280D01*
G03X311020Y169020I-7J940D01*
G02X311760Y169390I747J-570D01*
G01X313335D01*
G02X314075Y169020I-7J-940D01*
G03X314815Y168650I747J570D01*
G01X316390D01*
G03X317130Y169020I-7J940D01*
G02X317870Y169390I747J-570D01*
G01X319445D01*
G02X320185Y169020I-7J-940D01*
G03X320925Y168650I747J570D01*
G01X323500D01*
G03X324877Y169221I-1J1948D01*
G01X325244Y169587D01*
G01X302800Y137043D02*
G03X305600Y135481I2800J1729D01*
G01X312295D01*
G02X314049Y134755I1J-2480D01*
G02X314775Y133001I-1754J-1753D01*
G01Y89117D01*
G02X313424Y87150I-2107J0D01*
G01X313418Y87148D01*
G02X312638Y87004I-777J2023D01*
G01X300741D01*
G02X299476Y87247I1J3419D01*
G01X298584Y87602D01*
G03X298274Y87662I-311J-776D01*
G01X296983D01*
G03X295242Y86941I0J-2462D01*
G01X295000Y86699D01*
G01X302800Y132643D02*
G02X306500Y134206I3700J-3598D01*
G01X307075D01*
G02X307815Y133836I-7J-940D01*
G03X308555Y133466I747J570D01*
G01X310130D01*
G03X310870Y133836I-7J940D01*
G02X311610Y134206I747J-570D01*
G01X312295D01*
G02X313147Y133853I0J-1205D01*
G02X313500Y133001I-852J-852D01*
G01Y131426D01*
G02X313130Y130686I-940J7D01*
G03X312760Y129946I570J-747D01*
G01Y128371D01*
G03X313130Y127631I940J7D01*
G02X313500Y126891I-570J-747D01*
G01Y125316D01*
G02X313130Y124576I-940J7D01*
G03X312760Y123836I570J-747D01*
G01Y122261D01*
G03X313130Y121521I940J7D01*
G02X313500Y120781I-570J-747D01*
G01Y119206D01*
G02X313130Y118466I-940J7D01*
G03X312760Y117726I570J-747D01*
G01Y116151D01*
G03X313130Y115411I940J7D01*
G02X313500Y114671I-570J-747D01*
G01Y113096D01*
G02X313130Y112356I-940J7D01*
G03X312760Y111616I570J-747D01*
G01Y110041D01*
G03X313130Y109301I940J7D01*
G02X313500Y108561I-570J-747D01*
G01Y106986D01*
G02X313130Y106246I-940J7D01*
G03X312760Y105506I570J-747D01*
G01Y103931D01*
G03X313130Y103191I940J7D01*
G02X313500Y102451I-570J-747D01*
G01Y100876D01*
G02X313130Y100136I-940J7D01*
G03X312760Y99396I570J-747D01*
G01Y97821D01*
G03X313130Y97081I940J7D01*
G02X313500Y96341I-570J-747D01*
G01Y94766D01*
G02X313130Y94026I-940J7D01*
G03X312760Y93286I570J-747D01*
G01Y91711D01*
G03X313130Y90971I940J7D01*
G02X313500Y90231I-570J-747D01*
G01Y89117D01*
G02X312987Y88349I-831J0D01*
G01X312981Y88347D01*
G02X312639Y88279I-342J824D01*
G01X305277D01*
G02X304537Y88649I7J940D01*
G03X303797Y89019I-747J-570D01*
G01X302222D01*
G03X301482Y88649I7J-940D01*
G02X300742Y88279I-747J570D01*
G02X299948Y88432I1J2144D01*
G01X299056Y88787D01*
G03X298275Y88937I-782J-1961D01*
G01X296931D01*
G02X295277Y89622I0J2339D01*
G01X295000Y89899D01*
M02*
